# BASEBOARD_FAB2 (Tioga Pass) — schematic netlist excerpt (pin names and nets, part order shuffled) for the footprints in the layout excerpt that follows; sources: Cadence DE-HDL packaged netlist, KiCad conversion of Wiwynn_Tioga_Pass_MB.brd

R4F3  RES  2 1.0% CHIP  pkg 0402  page 98 : A = M_A_CPU_VREF ; B = M_A_VREF
R8G6  RES  2.26K 1.0% EMPTY  pkg 0402  page 159 : A = P3V3_STBY ; B = SMB_OCP_LAN_STBY_LVC3_SDA_R
C1B9  CAP_A  0.01UF 25V 10% X7R  pkg 0402V  page 83 : A = M_K_VREF ; B = GND

(kicad_pcb
	(version 20260206)
	(generator "pcbnew")
	(generator_version "10.0")
	(general
		(thickness 1.6)
		(legacy_teardrops no)
	)
	(paper "A4")
	(title_block
		(title "Wiwynn_Tioga_Pass_MB.brd")
		(comment 1 "Tioga Pass / footprints 1771-1773 of 4770")
	)
	(layers
		(0 "F.Cu" signal "TOP")
		(4 "In1.Cu" signal "L2GND")
		(6 "In2.Cu" signal "L3")
		(8 "In3.Cu" signal "L4GND")
		(10 "In4.Cu" signal "L5")
		(12 "In5.Cu" signal "L6GND")
		(14 "In6.Cu" signal "L7VCC")
		(16 "In7.Cu" signal "L8VCC")
		(18 "In8.Cu" signal "L9GND")
		(20 "In9.Cu" signal "L10")
		(22 "In10.Cu" signal "L11GND")
		(24 "In11.Cu" signal "L12")
		(26 "In12.Cu" signal "L13GND")
		(2 "B.Cu" signal "BOTTOM")
		(9 "F.Adhes" user "F.Adhesive")
		(11 "B.Adhes" user "B.Adhesive")
		(13 "F.Paste" user "Package Geometry/Pastemask Top")
		(15 "B.Paste" user "Package Geometry/Pastemask Bottom")
		(5 "F.SilkS" user "Ref Des/Silkscreen Top")
		(7 "B.SilkS" user "Ref Des/Silkscreen Bottom")
		(1 "F.Mask" user "Board Geometry/Soldermask Top")
		(3 "B.Mask" user "Board Geometry/Soldermask Bottom")
		(17 "Dwgs.User" user "User.Drawings")
		(19 "Cmts.User" user "User.Comments")
		(21 "Eco1.User" user "User.Eco1")
		(23 "Eco2.User" user "User.Eco2")
		(25 "Edge.Cuts" user "Board Geometry/Outline")
		(27 "Margin" user)
		(31 "F.CrtYd" user "Package Geometry/Place Bound Top")
		(29 "B.CrtYd" user "Package Geometry/Place Bound Bottom")
		(35 "F.Fab" user "Ref Des/Assembly Top")
		(33 "B.Fab" user "Ref Des/Assembly Bottom")
	)
	(footprint ""
		(layer "F.Cu")
		(at 192.786 -23.396194)
		(property "Reference" "R4F3"
			(at 0 0 0)
			(layer "F.SilkS")
			(hide yes)
			(effects
				(font
					(size 1.27 1.27)
				)
			)
		)
		(property "Value" ""
			(at 0 0 0)
			(layer "F.Fab")
			(effects
				(font
					(size 1.27 1.27)
				)
			)
		)
		(duplicate_pad_numbers_are_jumpers no)
		(fp_poly
			(pts
				(xy -0.2794 -0.1016) (xy 0.2794 -0.1016) (xy 0.2794 0.9906) (xy -0.2794 0.9906)
			)
			(stroke
				(width 0)
				(type default)
			)
			(fill no)
			(layer "F.CrtYd")
		)
		(fp_line
			(start -0.2794 -0.1016)
			(end -0.2794 0.9906)
			(stroke
				(width 0.1)
				(type default)
			)
			(layer "F.Fab")
		)
		(fp_line
			(start -0.2794 0.9906)
			(end 0.2794 0.9906)
			(stroke
				(width 0.1)
				(type default)
			)
			(layer "F.Fab")
		)
		(fp_line
			(start 0.2794 -0.1016)
			(end -0.2794 -0.1016)
			(stroke
				(width 0.1)
				(type default)
			)
			(layer "F.Fab")
		)
		(fp_line
			(start 0.2794 0.9906)
			(end 0.2794 -0.1016)
			(stroke
				(width 0.1)
				(type default)
			)
			(layer "F.Fab")
		)
		(pad "1" smd rect
			(at 0 0)
			(size 0.508 0.508)
			(layers "F.Cu" "F.Mask" "F.Paste")
			(net "M_A_CPU_VREF")
		)
		(pad "2" smd rect
			(at 0 0.889)
			(size 0.508 0.508)
			(layers "F.Cu" "F.Mask" "F.Paste")
			(net "M_A_VREF")
		)
		(zone
			(layer "F.Cu")
			(hatch none 0.5)
			(connect_pads
				(clearance 0)
			)
			(min_thickness 0.25)
			(keepout
				(tracks allowed)
				(vias not_allowed)
				(pads allowed)
				(copperpour not_allowed)
				(footprints allowed)
			)
			(placement
				(enabled no)
				(sheetname "")
			)
			(fill
				(thermal_gap 0.5)
				(thermal_bridge_width 0.5)
				(island_removal_mode 0)
			)
			(polygon
				(pts
					(xy 192.532 -23.142194) (xy 193.04 -23.142194) (xy 193.04 -22.761194) (xy 192.532 -22.761194)
				)
			)
		)
		(zone
			(layer "F.Cu")
			(hatch none 0.5)
			(connect_pads
				(clearance 0)
			)
			(min_thickness 0.25)
			(keepout
				(tracks not_allowed)
				(vias allowed)
				(pads allowed)
				(copperpour not_allowed)
				(footprints allowed)
			)
			(placement
				(enabled no)
				(sheetname "")
			)
			(fill
				(thermal_gap 0.5)
				(thermal_bridge_width 0.5)
				(island_removal_mode 0)
			)
			(polygon
				(pts
					(xy 192.532 -22.761194) (xy 193.04 -22.761194) (xy 193.04 -23.142194) (xy 192.532 -23.142194)
				)
			)
		)
	)
	(footprint ""
		(layer "F.Cu")
		(at 398.879568 -34.279586 90)
		(property "Reference" "R8G6"
			(at 0 0 90)
			(layer "F.SilkS")
			(hide yes)
			(effects
				(font
					(size 1.27 1.27)
				)
			)
		)
		(property "Value" ""
			(at 0 0 90)
			(layer "F.Fab")
			(effects
				(font
					(size 1.27 1.27)
				)
			)
		)
		(duplicate_pad_numbers_are_jumpers no)
		(fp_poly
			(pts
				(xy -0.2794 -0.1016) (xy 0.2794 -0.1016) (xy 0.2794 0.9906) (xy -0.2794 0.9906)
			)
			(stroke
				(width 0)
				(type default)
			)
			(fill no)
			(layer "F.CrtYd")
		)
		(fp_line
			(start 0.2794 -0.1016)
			(end -0.2794 -0.1016)
			(stroke
				(width 0.1)
				(type default)
			)
			(layer "F.Fab")
		)
		(fp_line
			(start -0.2794 -0.1016)
			(end -0.2794 0.9906)
			(stroke
				(width 0.1)
				(type default)
			)
			(layer "F.Fab")
		)
		(fp_line
			(start 0.2794 0.9906)
			(end 0.2794 -0.1016)
			(stroke
				(width 0.1)
				(type default)
			)
			(layer "F.Fab")
		)
		(fp_line
			(start -0.2794 0.9906)
			(end 0.2794 0.9906)
			(stroke
				(width 0.1)
				(type default)
			)
			(layer "F.Fab")
		)
		(pad "1" smd rect
			(at 0 0 90)
			(size 0.508 0.508)
			(layers "F.Cu" "F.Mask" "F.Paste")
			(net "P3V3_STBY")
		)
		(pad "2" smd rect
			(at 0 0.889 90)
			(size 0.508 0.508)
			(layers "F.Cu" "F.Mask" "F.Paste")
			(net "SMB_OCP_LAN_STBY_LVC3_SDA_R")
		)
		(zone
			(layer "F.Cu")
			(hatch none 0.5)
			(connect_pads
				(clearance 0)
			)
			(min_thickness 0.25)
			(keepout
				(tracks allowed)
				(vias not_allowed)
				(pads allowed)
				(copperpour not_allowed)
				(footprints allowed)
			)
			(placement
				(enabled no)
				(sheetname "")
			)
			(fill
				(thermal_gap 0.5)
				(thermal_bridge_width 0.5)
				(island_removal_mode 0)
			)
			(polygon
				(pts
					(xy 399.133568 -34.025586) (xy 399.133568 -34.533586) (xy 399.514568 -34.533586) (xy 399.514568 -34.025586)
				)
			)
		)
		(zone
			(layer "F.Cu")
			(hatch none 0.5)
			(connect_pads
				(clearance 0)
			)
			(min_thickness 0.25)
			(keepout
				(tracks not_allowed)
				(vias allowed)
				(pads allowed)
				(copperpour not_allowed)
				(footprints allowed)
			)
			(placement
				(enabled no)
				(sheetname "")
			)
			(fill
				(thermal_gap 0.5)
				(thermal_bridge_width 0.5)
				(island_removal_mode 0)
			)
			(polygon
				(pts
					(xy 399.514568 -34.025586) (xy 399.514568 -34.533586) (xy 399.133568 -34.533586) (xy 399.133568 -34.025586)
				)
			)
		)
	)
	(footprint ""
		(layer "F.Cu")
		(at 30.554168 -128.8542 90)
		(property "Reference" "C1B9"
			(at 0 0 90)
			(layer "F.SilkS")
			(hide yes)
			(effects
				(font
					(size 1.27 1.27)
				)
			)
		)
		(property "Value" ""
			(at 0 0 90)
			(layer "F.Fab")
			(effects
				(font
					(size 1.27 1.27)
				)
			)
		)
		(duplicate_pad_numbers_are_jumpers no)
		(fp_poly
			(pts
				(xy 0.3048 -0.1016) (xy 0.3048 0.9906) (xy -0.3048 0.9906) (xy -0.3048 -0.1016)
			)
			(stroke
				(width 0)
				(type default)
			)
			(fill no)
			(layer "F.CrtYd")
		)
		(fp_line
			(start 0.3048 -0.1016)
			(end -0.3048 -0.1016)
			(stroke
				(width 0.1)
				(type default)
			)
			(layer "F.Fab")
		)
		(fp_line
			(start -0.3048 -0.1016)
			(end -0.3048 0.9906)
			(stroke
				(width 0.1)
				(type default)
			)
			(layer "F.Fab")
		)
		(fp_line
			(start 0.3048 0.9906)
			(end 0.3048 -0.1016)
			(stroke
				(width 0.1)
				(type default)
			)
			(layer "F.Fab")
		)
		(fp_line
			(start -0.3048 0.9906)
			(end 0.3048 0.9906)
			(stroke
				(width 0.1)
				(type default)
			)
			(layer "F.Fab")
		)
		(pad "1" smd rect
			(at 0 0 90)
			(size 0.508 0.508)
			(layers "F.Cu" "F.Mask" "F.Paste")
			(net "M_K_VREF")
		)
		(pad "2" smd rect
			(at 0 0.889 90)
			(size 0.508 0.508)
			(layers "F.Cu" "F.Mask" "F.Paste")
			(net "GND")
		)
		(zone
			(layer "F.Cu")
			(hatch none 0.5)
			(connect_pads
				(clearance 0)
			)
			(min_thickness 0.25)
			(keepout
				(tracks allowed)
				(vias not_allowed)
				(pads allowed)
				(copperpour not_allowed)
				(footprints allowed)
			)
			(placement
				(enabled no)
				(sheetname "")
			)
			(fill
				(thermal_gap 0.5)
				(thermal_bridge_width 0.5)
				(island_removal_mode 0)
			)
			(polygon
				(pts
					(xy 30.808168 -128.6002) (xy 30.808168 -129.1082) (xy 31.189168 -129.1082) (xy 31.189168 -128.6002)
				)
			)
		)
		(zone
			(layer "F.Cu")
			(hatch none 0.5)
			(connect_pads
				(clearance 0)
			)
			(min_thickness 0.25)
			(keepout
				(tracks not_allowed)
				(vias allowed)
				(pads allowed)
				(copperpour not_allowed)
				(footprints allowed)
			)
			(placement
				(enabled no)
				(sheetname "")
			)
			(fill
				(thermal_gap 0.5)
				(thermal_bridge_width 0.5)
				(island_removal_mode 0)
			)
			(polygon
				(pts
					(xy 31.189168 -128.6002) (xy 31.189168 -129.1082) (xy 30.808168 -129.1082) (xy 30.808168 -128.6002)
				)
			)
		)
	)
)
